(kicad_pcb
	(version 20260206)
	(generator "pcbnew")
	(generator_version "10.0")
	(general
		(thickness 1.6)
		(legacy_teardrops no)
	)
	(paper "A4")
	(title_block
		(title "Wiwynn_Tioga_Pass_MB.brd")
		(comment 1 "Tioga Pass / footprints 570-576 of 4770")
	)
	(layers
		(0 "F.Cu" signal "TOP")
		(4 "In1.Cu" signal "L2GND")
		(6 "In2.Cu" signal "L3")
		(8 "In3.Cu" signal "L4GND")
		(10 "In4.Cu" signal "L5")
		(12 "In5.Cu" signal "L6GND")
		(14 "In6.Cu" signal "L7VCC")
		(16 "In7.Cu" signal "L8VCC")
		(18 "In8.Cu" signal "L9GND")
		(20 "In9.Cu" signal "L10")
		(22 "In10.Cu" signal "L11GND")
		(24 "In11.Cu" signal "L12")
		(26 "In12.Cu" signal "L13GND")
		(2 "B.Cu" signal "BOTTOM")
		(9 "F.Adhes" user "F.Adhesive")
		(11 "B.Adhes" user "B.Adhesive")
		(13 "F.Paste" user "Package Geometry/Pastemask Top")
		(15 "B.Paste" user "Package Geometry/Pastemask Bottom")
		(5 "F.SilkS" user "Ref Des/Silkscreen Top")
		(7 "B.SilkS" user "Ref Des/Silkscreen Bottom")
		(1 "F.Mask" user "Board Geometry/Soldermask Top")
		(3 "B.Mask" user "Board Geometry/Soldermask Bottom")
		(17 "Dwgs.User" user "User.Drawings")
		(19 "Cmts.User" user "User.Comments")
		(21 "Eco1.User" user "User.Eco1")
		(23 "Eco2.User" user "User.Eco2")
		(25 "Edge.Cuts" user "Board Geometry/Outline")
		(27 "Margin" user)
		(31 "F.CrtYd" user "Package Geometry/Place Bound Top")
		(29 "B.CrtYd" user "Package Geometry/Place Bound Bottom")
		(35 "F.Fab" user "Ref Des/Assembly Top")
		(33 "B.Fab" user "Ref Des/Assembly Bottom")
	)
	(footprint ""
		(layer "F.Cu")
		(at 353.5807 -15.737586 90)
		(property "Reference" "C7G2"
			(at -4.21767 2.921 0)
			(unlocked yes)
			(layer "F.SilkS")
			(effects
				(font
					(size 0.7874 0.5842)
					(thickness 0.1524)
				)
				(justify left)
			)
		)
		(property "Value" ""
			(at 0 0 90)
			(layer "F.Fab")
			(effects
				(font
					(size 1.27 1.27)
				)
			)
		)
		(duplicate_pad_numbers_are_jumpers no)
		(fp_line
			(start 0.9017 -1.714246)
			(end 0.7239 -1.714246)
			(stroke
				(width 0.1524)
				(type default)
			)
			(layer "F.SilkS")
		)
		(fp_line
			(start -0.7239 -1.714246)
			(end -0.9017 -1.714246)
			(stroke
				(width 0.1524)
				(type default)
			)
			(layer "F.SilkS")
		)
		(fp_line
			(start -0.9017 -1.714246)
			(end -0.9017 1.587754)
			(stroke
				(width 0.1524)
				(type default)
			)
			(layer "F.SilkS")
		)
		(fp_line
			(start 2.638044 -0.733044)
			(end 0.9017 -0.733044)
			(stroke
				(width 0.1524)
				(type default)
			)
			(layer "F.SilkS")
		)
		(fp_line
			(start -0.9017 -0.733044)
			(end -2.638044 -0.733044)
			(stroke
				(width 0.1524)
				(type default)
			)
			(layer "F.SilkS")
		)
		(fp_line
			(start -2.638044 -0.733044)
			(end -3.400044 0.028956)
			(stroke
				(width 0.1524)
				(type default)
			)
			(layer "F.SilkS")
		)
		(fp_line
			(start 3.400044 0.028956)
			(end 2.638044 -0.733044)
			(stroke
				(width 0.1524)
				(type default)
			)
			(layer "F.SilkS")
		)
		(fp_line
			(start -3.400044 0.028956)
			(end -3.400044 6.067044)
			(stroke
				(width 0.1524)
				(type default)
			)
			(layer "F.SilkS")
		)
		(fp_line
			(start 0.9017 1.587754)
			(end 0.9017 -1.714246)
			(stroke
				(width 0.1524)
				(type default)
			)
			(layer "F.SilkS")
		)
		(fp_line
			(start 0.7239 1.587754)
			(end 0.9017 1.587754)
			(stroke
				(width 0.1524)
				(type default)
			)
			(layer "F.SilkS")
		)
		(fp_line
			(start -0.9017 1.587754)
			(end -0.7239 1.587754)
			(stroke
				(width 0.1524)
				(type default)
			)
			(layer "F.SilkS")
		)
		(fp_line
			(start 3.400044 6.067044)
			(end 3.400044 0.028956)
			(stroke
				(width 0.1524)
				(type default)
			)
			(layer "F.SilkS")
		)
		(fp_line
			(start 0.9017 6.067044)
			(end 3.400044 6.067044)
			(stroke
				(width 0.1524)
				(type default)
			)
			(layer "F.SilkS")
		)
		(fp_line
			(start -3.400044 6.067044)
			(end -0.9017 6.067044)
			(stroke
				(width 0.1524)
				(type default)
			)
			(layer "F.SilkS")
		)
		(fp_poly
			(pts
				(xy -3.400044 6.067044) (xy 3.400044 6.067044) (xy 3.400044 0.028956) (xy 2.638044 -0.733044) (xy -2.638044 -0.733044)
				(xy -3.400044 0.028956)
			)
			(stroke
				(width 0)
				(type default)
			)
			(fill no)
			(layer "F.CrtYd")
		)
		(fp_line
			(start 2.638044 -0.733044)
			(end -2.638044 -0.733044)
			(stroke
				(width 0.1)
				(type default)
			)
			(layer "F.Fab")
		)
		(fp_line
			(start -2.638044 -0.733044)
			(end -3.400044 0.028956)
			(stroke
				(width 0.1)
				(type default)
			)
			(layer "F.Fab")
		)
		(fp_line
			(start 3.400044 0.028956)
			(end 2.638044 -0.733044)
			(stroke
				(width 0.1)
				(type default)
			)
			(layer "F.Fab")
		)
		(fp_line
			(start -3.400044 0.028956)
			(end -3.400044 6.067044)
			(stroke
				(width 0.1)
				(type default)
			)
			(layer "F.Fab")
		)
		(fp_line
			(start 3.400044 6.067044)
			(end 3.400044 0.028956)
			(stroke
				(width 0.1)
				(type default)
			)
			(layer "F.Fab")
		)
		(fp_line
			(start -3.400044 6.067044)
			(end 3.400044 6.067044)
			(stroke
				(width 0.1)
				(type default)
			)
			(layer "F.Fab")
		)
		(fp_circle
			(center 0 2.667)
			(end 0 6.067044)
			(stroke
				(width 0.1)
				(type default)
			)
			(fill no)
			(layer "F.Fab")
		)
		(pad "1" smd rect
			(at 0 0 90)
			(size 0.7874 3.429)
			(layers "F.Cu" "F.Mask" "F.Paste")
			(net "VR_FET_SW_P12V_STBY_PVDDQ_ABC")
		)
		(pad "2" smd rect
			(at 0 5.334 90)
			(size 0.7874 3.429)
			(layers "F.Cu" "F.Mask" "F.Paste")
			(net "GND")
		)
	)
	(footprint ""
		(layer "F.Cu")
		(at 482.67366 -29.28112 90)
		(property "Reference" "R8F27"
			(at 0 0 90)
			(layer "F.SilkS")
			(hide yes)
			(effects
				(font
					(size 1.27 1.27)
				)
			)
		)
		(property "Value" ""
			(at 0 0 90)
			(layer "F.Fab")
			(effects
				(font
					(size 1.27 1.27)
				)
			)
		)
		(duplicate_pad_numbers_are_jumpers no)
		(fp_poly
			(pts
				(xy -0.2794 -0.1016) (xy 0.2794 -0.1016) (xy 0.2794 0.9906) (xy -0.2794 0.9906)
			)
			(stroke
				(width 0)
				(type default)
			)
			(fill no)
			(layer "F.CrtYd")
		)
		(fp_line
			(start 0.2794 -0.1016)
			(end -0.2794 -0.1016)
			(stroke
				(width 0.1)
				(type default)
			)
			(layer "F.Fab")
		)
		(fp_line
			(start -0.2794 -0.1016)
			(end -0.2794 0.9906)
			(stroke
				(width 0.1)
				(type default)
			)
			(layer "F.Fab")
		)
		(fp_line
			(start 0.2794 0.9906)
			(end 0.2794 -0.1016)
			(stroke
				(width 0.1)
				(type default)
			)
			(layer "F.Fab")
		)
		(fp_line
			(start -0.2794 0.9906)
			(end 0.2794 0.9906)
			(stroke
				(width 0.1)
				(type default)
			)
			(layer "F.Fab")
		)
		(pad "1" smd rect
			(at 0 0 90)
			(size 0.508 0.508)
			(layers "F.Cu" "F.Mask" "F.Paste")
			(net "CLK_32K_SUSCLK_PLD_R")
		)
		(pad "2" smd rect
			(at 0 0.889 90)
			(size 0.508 0.508)
			(layers "F.Cu" "F.Mask" "F.Paste")
			(net "CLK_32K_SUSCLK_PLD")
		)
		(zone
			(layer "F.Cu")
			(hatch none 0.5)
			(connect_pads
				(clearance 0)
			)
			(min_thickness 0.25)
			(keepout
				(tracks allowed)
				(vias not_allowed)
				(pads allowed)
				(copperpour not_allowed)
				(footprints allowed)
			)
			(placement
				(enabled no)
				(sheetname "")
			)
			(fill
				(thermal_gap 0.5)
				(thermal_bridge_width 0.5)
				(island_removal_mode 0)
			)
			(polygon
				(pts
					(xy 482.92766 -29.02712) (xy 482.92766 -29.53512) (xy 483.30866 -29.53512) (xy 483.30866 -29.02712)
				)
			)
		)
		(zone
			(layer "F.Cu")
			(hatch none 0.5)
			(connect_pads
				(clearance 0)
			)
			(min_thickness 0.25)
			(keepout
				(tracks not_allowed)
				(vias allowed)
				(pads allowed)
				(copperpour not_allowed)
				(footprints allowed)
			)
			(placement
				(enabled no)
				(sheetname "")
			)
			(fill
				(thermal_gap 0.5)
				(thermal_bridge_width 0.5)
				(island_removal_mode 0)
			)
			(polygon
				(pts
					(xy 483.30866 -29.02712) (xy 483.30866 -29.53512) (xy 482.92766 -29.53512) (xy 482.92766 -29.02712)
				)
			)
		)
	)
	(footprint ""
		(layer "F.Cu")
		(at 355.24948 -135.742934)
		(property "Reference" "C7A38"
			(at 0 0 0)
			(layer "F.SilkS")
			(hide yes)
			(effects
				(font
					(size 1.27 1.27)
				)
			)
		)
		(property "Value" ""
			(at 0 0 0)
			(layer "F.Fab")
			(effects
				(font
					(size 1.27 1.27)
				)
			)
		)
		(duplicate_pad_numbers_are_jumpers no)
		(fp_rect
			(start -0.3048 0.9906)
			(end 0.3048 -0.1016)
			(stroke
				(width 0)
				(type default)
			)
			(fill no)
			(layer "F.CrtYd")
		)
		(fp_line
			(start -0.3048 -0.1016)
			(end -0.3048 0.9906)
			(stroke
				(width 0.1)
				(type default)
			)
			(layer "F.Fab")
		)
		(fp_line
			(start -0.3048 0.9906)
			(end 0.3048 0.9906)
			(stroke
				(width 0.1)
				(type default)
			)
			(layer "F.Fab")
		)
		(fp_line
			(start 0.3048 -0.1016)
			(end -0.3048 -0.1016)
			(stroke
				(width 0.1)
				(type default)
			)
			(layer "F.Fab")
		)
		(fp_line
			(start 0.3048 0.9906)
			(end 0.3048 -0.1016)
			(stroke
				(width 0.1)
				(type default)
			)
			(layer "F.Fab")
		)
		(pad "1" smd rect
			(at 0 0)
			(size 0.508 0.508)
			(layers "F.Cu" "F.Mask" "F.Paste")
			(net "VR_PVDDQ_DEF_VDD")
		)
		(pad "2" smd rect
			(at 0 0.889)
			(size 0.508 0.508)
			(layers "F.Cu" "F.Mask" "F.Paste")
			(net "GND")
		)
		(zone
			(layer "F.Cu")
			(hatch none 0.5)
			(connect_pads
				(clearance 0)
			)
			(min_thickness 0.25)
			(keepout
				(tracks not_allowed)
				(vias allowed)
				(pads allowed)
				(copperpour not_allowed)
				(footprints allowed)
			)
			(placement
				(enabled no)
				(sheetname "")
			)
			(fill
				(thermal_gap 0.5)
				(thermal_bridge_width 0.5)
				(island_removal_mode 0)
			)
			(polygon
				(pts
					(xy 354.99548 -135.107934) (xy 355.50348 -135.107934) (xy 355.50348 -135.488934) (xy 354.99548 -135.488934)
				)
			)
		)
		(zone
			(layer "F.Cu")
			(hatch none 0.5)
			(connect_pads
				(clearance 0)
			)
			(min_thickness 0.25)
			(keepout
				(tracks allowed)
				(vias not_allowed)
				(pads allowed)
				(copperpour not_allowed)
				(footprints allowed)
			)
			(placement
				(enabled no)
				(sheetname "")
			)
			(fill
				(thermal_gap 0.5)
				(thermal_bridge_width 0.5)
				(island_removal_mode 0)
			)
			(polygon
				(pts
					(xy 354.99548 -135.107934) (xy 355.50348 -135.107934) (xy 355.50348 -135.488934) (xy 354.99548 -135.488934)
				)
			)
		)
	)
	(footprint ""
		(layer "F.Cu")
		(at 176.0855 -7.874 90)
		(property "Reference" "C4G10"
			(at 0 0 90)
			(layer "F.SilkS")
			(hide yes)
			(effects
				(font
					(size 1.27 1.27)
				)
			)
		)
		(property "Value" ""
			(at 0 0 90)
			(layer "F.Fab")
			(effects
				(font
					(size 1.27 1.27)
				)
			)
		)
		(duplicate_pad_numbers_are_jumpers no)
		(fp_poly
			(pts
				(xy 0.3048 -0.1016) (xy 0.3048 0.9906) (xy -0.3048 0.9906) (xy -0.3048 -0.1016)
			)
			(stroke
				(width 0)
				(type default)
			)
			(fill no)
			(layer "F.CrtYd")
		)
		(fp_line
			(start 0.3048 -0.1016)
			(end -0.3048 -0.1016)
			(stroke
				(width 0.1)
				(type default)
			)
			(layer "F.Fab")
		)
		(fp_line
			(start -0.3048 -0.1016)
			(end -0.3048 0.9906)
			(stroke
				(width 0.1)
				(type default)
			)
			(layer "F.Fab")
		)
		(fp_line
			(start 0.3048 0.9906)
			(end 0.3048 -0.1016)
			(stroke
				(width 0.1)
				(type default)
			)
			(layer "F.Fab")
		)
		(fp_line
			(start -0.3048 0.9906)
			(end 0.3048 0.9906)
			(stroke
				(width 0.1)
				(type default)
			)
			(layer "F.Fab")
		)
		(pad "1" smd rect
			(at 0 0 90)
			(size 0.508 0.508)
			(layers "F.Cu" "F.Mask" "F.Paste")
			(net "VR_COMP_RC_PVPP_GHJ")
		)
		(pad "2" smd rect
			(at 0 0.889 90)
			(size 0.508 0.508)
			(layers "F.Cu" "F.Mask" "F.Paste")
			(net "VR_COMP_PVPP_GHJ_3")
		)
		(zone
			(layer "F.Cu")
			(hatch none 0.5)
			(connect_pads
				(clearance 0)
			)
			(min_thickness 0.25)
			(keepout
				(tracks allowed)
				(vias not_allowed)
				(pads allowed)
				(copperpour not_allowed)
				(footprints allowed)
			)
			(placement
				(enabled no)
				(sheetname "")
			)
			(fill
				(thermal_gap 0.5)
				(thermal_bridge_width 0.5)
				(island_removal_mode 0)
			)
			(polygon
				(pts
					(xy 176.3395 -7.62) (xy 176.3395 -8.128) (xy 176.7205 -8.128) (xy 176.7205 -7.62)
				)
			)
		)
		(zone
			(layer "F.Cu")
			(hatch none 0.5)
			(connect_pads
				(clearance 0)
			)
			(min_thickness 0.25)
			(keepout
				(tracks not_allowed)
				(vias allowed)
				(pads allowed)
				(copperpour not_allowed)
				(footprints allowed)
			)
			(placement
				(enabled no)
				(sheetname "")
			)
			(fill
				(thermal_gap 0.5)
				(thermal_bridge_width 0.5)
				(island_removal_mode 0)
			)
			(polygon
				(pts
					(xy 176.7205 -7.62) (xy 176.7205 -8.128) (xy 176.3395 -8.128) (xy 176.3395 -7.62)
				)
			)
		)
	)
	(footprint ""
		(layer "F.Cu")
		(at 156.70022 -123.7107)
		(property "Reference" "U3B1"
			(at 4.46278 3.54457 0)
			(unlocked yes)
			(layer "F.SilkS")
			(effects
				(font
					(size 0.7874 0.5842)
					(thickness 0.1524)
				)
			)
		)
		(property "Value" ""
			(at 0 0 0)
			(layer "F.Fab")
			(effects
				(font
					(size 1.27 1.27)
				)
			)
		)
		(duplicate_pad_numbers_are_jumpers no)
		(fp_line
			(start 3.225038 2.52476)
			(end 1.348486 2.52476)
			(stroke
				(width 0.1524)
				(type default)
			)
			(layer "F.SilkS")
		)
		(fp_line
			(start 3.225292 -0.57404)
			(end 1.352804 -0.57404)
			(stroke
				(width 0.1524)
				(type default)
			)
			(layer "F.SilkS")
		)
		(fp_circle
			(center -1.454404 -0.556514)
			(end -1.327404 -0.556514)
			(stroke
				(width 0.254)
				(type default)
			)
			(fill no)
			(layer "F.SilkS")
		)
		(fp_poly
			(pts
				(xy 0.7366 -0.57404) (xy 3.8354 -0.57404) (xy 3.8354 2.52476) (xy 0.7366 2.52476)
			)
			(stroke
				(width 0)
				(type default)
			)
			(fill no)
			(layer "F.CrtYd")
		)
		(fp_line
			(start 0.7366 -0.57404)
			(end 3.8354 -0.57404)
			(stroke
				(width 0.1)
				(type default)
			)
			(layer "F.Fab")
		)
		(fp_line
			(start 0.7366 2.52476)
			(end 0.7366 -0.57404)
			(stroke
				(width 0.1)
				(type default)
			)
			(layer "F.Fab")
		)
		(fp_line
			(start 3.8354 -0.57404)
			(end 3.8354 2.52476)
			(stroke
				(width 0.1)
				(type default)
			)
			(layer "F.Fab")
		)
		(fp_line
			(start 3.8354 2.52476)
			(end 0.7366 2.52476)
			(stroke
				(width 0.1)
				(type default)
			)
			(layer "F.Fab")
		)
		(fp_circle
			(center -1.454404 -0.556514)
			(end -1.327404 -0.556514)
			(stroke
				(width 0.254)
				(type default)
			)
			(fill no)
			(layer "F.Fab")
		)
		(pad "1" smd rect
			(at 0 0)
			(size 1.778 0.4572)
			(layers "F.Cu" "F.Mask" "F.Paste")
			(net "PVCCIO_CPU1")
		)
		(pad "2" smd rect
			(at 0 0.65024)
			(size 1.778 0.4572)
			(layers "F.Cu" "F.Mask" "F.Paste")
			(net "SMB_DDR_KLM_SCL_G")
		)
		(pad "3" smd rect
			(at 0 1.30048)
			(size 1.778 0.4572)
			(layers "F.Cu" "F.Mask" "F.Paste")
			(net "SMB_DDR_KLM_SDA_G")
		)
		(pad "4" smd rect
			(at 0 1.95072)
			(size 1.778 0.4572)
			(layers "F.Cu" "F.Mask" "F.Paste")
			(net "GND")
		)
		(pad "5" smd rect
			(at 4.572 1.95072)
			(size 1.778 0.4572)
			(layers "F.Cu" "F.Mask" "F.Paste")
			(net "TP_SMB_DDR_KLM_EN")
		)
		(pad "6" smd rect
			(at 4.572 1.30048)
			(size 1.778 0.4572)
			(layers "F.Cu" "F.Mask" "F.Paste")
			(net "SMB_DDR_KLM_VPP_SDA_R")
		)
		(pad "7" smd rect
			(at 4.572 0.65024)
			(size 1.778 0.4572)
			(layers "F.Cu" "F.Mask" "F.Paste")
			(net "SMB_DDR_KLM_VPP_SCL_R")
		)
		(pad "8" smd rect
			(at 4.572 0)
			(size 1.778 0.4572)
			(layers "F.Cu" "F.Mask" "F.Paste")
			(net "PVPP_KLM")
		)
	)
	(footprint ""
		(layer "F.Cu")
		(at 372.0084 -131.7498 180)
		(property "Reference" "C7B23"
			(at 0 0 180)
			(layer "F.SilkS")
			(hide yes)
			(effects
				(font
					(size 1.27 1.27)
				)
			)
		)
		(property "Value" ""
			(at 0 0 180)
			(layer "F.Fab")
			(effects
				(font
					(size 1.27 1.27)
				)
			)
		)
		(duplicate_pad_numbers_are_jumpers no)
		(fp_poly
			(pts
				(xy -0.4953 -0.2032) (xy 0.4953 -0.2032) (xy 0.4953 1.6002) (xy -0.4953 1.6002)
			)
			(stroke
				(width 0)
				(type default)
			)
			(fill no)
			(layer "F.CrtYd")
		)
		(fp_line
			(start 0.4953 1.6002)
			(end -0.4953 1.6002)
			(stroke
				(width 0.1)
				(type default)
			)
			(layer "F.Fab")
		)
		(fp_line
			(start 0.4953 -0.2032)
			(end 0.4953 1.6002)
			(stroke
				(width 0.1)
				(type default)
			)
			(layer "F.Fab")
		)
		(fp_line
			(start -0.4953 1.6002)
			(end -0.4953 -0.2032)
			(stroke
				(width 0.1)
				(type default)
			)
			(layer "F.Fab")
		)
		(fp_line
			(start -0.4953 -0.2032)
			(end 0.4953 -0.2032)
			(stroke
				(width 0.1)
				(type default)
			)
			(layer "F.Fab")
		)
		(pad "1" smd rect
			(at 0 0 180)
			(size 0.762 0.889)
			(layers "F.Cu" "F.Mask" "F.Paste")
			(net "P1V05_PCH_STBY")
		)
		(pad "2" smd rect
			(at 0 1.397 180)
			(size 0.762 0.889)
			(layers "F.Cu" "F.Mask" "F.Paste")
			(net "GND")
		)
		(zone
			(layer "F.Cu")
			(hatch none 0.5)
			(connect_pads
				(clearance 0)
			)
			(min_thickness 0.25)
			(keepout
				(tracks not_allowed)
				(vias allowed)
				(pads allowed)
				(copperpour not_allowed)
				(footprints allowed)
			)
			(placement
				(enabled no)
				(sheetname "")
			)
			(fill
				(thermal_gap 0.5)
				(thermal_bridge_width 0.5)
				(island_removal_mode 0)
			)
			(polygon
				(pts
					(xy 372.3894 -132.1943) (xy 371.6274 -132.1943) (xy 371.6274 -132.7023) (xy 372.3894 -132.7023)
				)
			)
		)
	)
	(footprint ""
		(layer "F.Cu")
		(at 163.576 -77.978 -90)
		(property "Reference" "R4D23"
			(at 0 0 270)
			(layer "F.SilkS")
			(hide yes)
			(effects
				(font
					(size 1.27 1.27)
				)
			)
		)
		(property "Value" ""
			(at 0 0 270)
			(layer "F.Fab")
			(effects
				(font
					(size 1.27 1.27)
				)
			)
		)
		(duplicate_pad_numbers_are_jumpers no)
		(fp_poly
			(pts
				(xy -0.2794 -0.1016) (xy 0.2794 -0.1016) (xy 0.2794 0.9906) (xy -0.2794 0.9906)
			)
			(stroke
				(width 0)
				(type default)
			)
			(fill no)
			(layer "F.CrtYd")
		)
		(fp_line
			(start -0.2794 0.9906)
			(end 0.2794 0.9906)
			(stroke
				(width 0.1)
				(type default)
			)
			(layer "F.Fab")
		)
		(fp_line
			(start 0.2794 0.9906)
			(end 0.2794 -0.1016)
			(stroke
				(width 0.1)
				(type default)
			)
			(layer "F.Fab")
		)
		(fp_line
			(start -0.2794 -0.1016)
			(end -0.2794 0.9906)
			(stroke
				(width 0.1)
				(type default)
			)
			(layer "F.Fab")
		)
		(fp_line
			(start 0.2794 -0.1016)
			(end -0.2794 -0.1016)
			(stroke
				(width 0.1)
				(type default)
			)
			(layer "F.Fab")
		)
		(pad "1" smd rect
			(at 0 0 270)
			(size 0.508 0.508)
			(layers "F.Cu" "F.Mask" "F.Paste")
			(net "CLK_100M_CPU1_RC_REFCLK1_R_DP")
		)
		(pad "2" smd rect
			(at 0 0.889 270)
			(size 0.508 0.508)
			(layers "F.Cu" "F.Mask" "F.Paste")
			(net "CLK_100M_CPU1_RC_REFCLK1_DP")
		)
		(zone
			(layer "F.Cu")
			(hatch none 0.5)
			(connect_pads
				(clearance 0)
			)
			(min_thickness 0.25)
			(keepout
				(tracks not_allowed)
				(vias allowed)
				(pads allowed)
				(copperpour not_allowed)
				(footprints allowed)
			)
			(placement
				(enabled no)
				(sheetname "")
			)
			(fill
				(thermal_gap 0.5)
				(thermal_bridge_width 0.5)
				(island_removal_mode 0)
			)
			(polygon
				(pts
					(xy 162.941 -78.232) (xy 162.941 -77.724) (xy 163.322 -77.724) (xy 163.322 -78.232)
				)
			)
		)
		(zone
			(layer "F.Cu")
			(hatch none 0.5)
			(connect_pads
				(clearance 0)
			)
			(min_thickness 0.25)
			(keepout
				(tracks allowed)
				(vias not_allowed)
				(pads allowed)
				(copperpour not_allowed)
				(footprints allowed)
			)
			(placement
				(enabled no)
				(sheetname "")
			)
			(fill
				(thermal_gap 0.5)
				(thermal_bridge_width 0.5)
				(island_removal_mode 0)
			)
			(polygon
				(pts
					(xy 163.322 -78.232) (xy 163.322 -77.724) (xy 162.941 -77.724) (xy 162.941 -78.232)
				)
			)
		)
	)
)
